FILE_TYPE=LIBRARY_PARTS;
primitive 'FET_N_DUAL','FET_N_DUAL_SM','FET_N_DUAL_SMLF';
  pin
    'GATE<0>':
      PIN_NUMBER='(2,5)';
      PINUSE='UNSPEC';
      NO_LOAD_CHECK='BOTH';
      NO_IO_CHECK='BOTH';
      ALLOW_CONNECT='TRUE';
    'SOURCE<0>':
      PIN_NUMBER='(1,4)';
      PINUSE='UNSPEC';
      NO_LOAD_CHECK='BOTH';
      NO_IO_CHECK='BOTH';
      ALLOW_CONNECT='TRUE';
    'DRAIN<0>':
      PIN_NUMBER='(6,3)';
      PINUSE='UNSPEC';
      NO_LOAD_CHECK='BOTH';
      NO_IO_CHECK='BOTH';
      ALLOW_CONNECT='TRUE';
  end_pin;
  body
    CLASS='IC';
    PART_NAME='FET_N_DUAL';
    PHYS_DES_PREFIX='Q';
  end_body;
end_primitive;
primitive 'FET_N_DUAL_MLFP';
  pin
    'GATE<0>':
      PIN_NUMBER='(2,4)';
      PINUSE='UNSPEC';
      NO_LOAD_CHECK='BOTH';
      NO_IO_CHECK='BOTH';
      ALLOW_CONNECT='TRUE';
    'SOURCE<0>':
      PIN_NUMBER='(1,3)';
      PINUSE='UNSPEC';
      NO_LOAD_CHECK='BOTH';
      NO_IO_CHECK='BOTH';
      ALLOW_CONNECT='TRUE';
    'DRAIN<0>':
      PIN_NUMBER='(7,5)';
      PINUSE='UNSPEC';
      NO_LOAD_CHECK='BOTH';
      NO_IO_CHECK='BOTH';
      ALLOW_CONNECT='TRUE';
  end_pin;
  body
    PART_NAME='FET_N_DUAL';
    PHYS_DES_PREFIX='Q';
  end_body;
end_primitive;
primitive 'FET_N_DUAL_SMLFJIC';
  pin
    'GATE<0>':
      PIN_NUMBER='(1,4)';
      PINUSE='UNSPEC';
      NO_LOAD_CHECK='BOTH';
      NO_IO_CHECK='BOTH';
      ALLOW_CONNECT='TRUE';
    'SOURCE<0>':
      PIN_NUMBER='(2,5)';
      PINUSE='UNSPEC';
      NO_LOAD_CHECK='BOTH';
      NO_IO_CHECK='BOTH';
      ALLOW_CONNECT='TRUE';
    'DRAIN<0>':
      PIN_NUMBER='(6,3)';
      PINUSE='UNSPEC';
      NO_LOAD_CHECK='BOTH';
      NO_IO_CHECK='BOTH';
      ALLOW_CONNECT='TRUE';
  end_pin;
  body
    CLASS='IC';
    PART_NAME='FET_N_DUAL';
    PHYS_DES_PREFIX='Q';
  end_body;
end_primitive;

END.
